(kicad_pcb
	(version 20260206)
	(generator "pcbnew")
	(generator_version "10.0")
	(general
		(thickness 1.6)
		(legacy_teardrops no)
	)
	(paper "A4")
	(title_block
		(title "Wiwynn_Tioga_Pass_MB.brd")
		(comment 1 "Tioga Pass / footprint 2254 of 4770 (U5D1), pads 1016-1121 of 3647")
	)
	(layers
		(0 "F.Cu" signal "TOP")
		(4 "In1.Cu" signal "L2GND")
		(6 "In2.Cu" signal "L3")
		(8 "In3.Cu" signal "L4GND")
		(10 "In4.Cu" signal "L5")
		(12 "In5.Cu" signal "L6GND")
		(14 "In6.Cu" signal "L7VCC")
		(16 "In7.Cu" signal "L8VCC")
		(18 "In8.Cu" signal "L9GND")
		(20 "In9.Cu" signal "L10")
		(22 "In10.Cu" signal "L11GND")
		(24 "In11.Cu" signal "L12")
		(26 "In12.Cu" signal "L13GND")
		(2 "B.Cu" signal "BOTTOM")
		(9 "F.Adhes" user "F.Adhesive")
		(11 "B.Adhes" user "B.Adhesive")
		(13 "F.Paste" user "Package Geometry/Pastemask Top")
		(15 "B.Paste" user "Package Geometry/Pastemask Bottom")
		(5 "F.SilkS" user "Ref Des/Silkscreen Top")
		(7 "B.SilkS" user "Ref Des/Silkscreen Bottom")
		(1 "F.Mask" user "Board Geometry/Soldermask Top")
		(3 "B.Mask" user "Board Geometry/Soldermask Bottom")
		(17 "Dwgs.User" user "User.Drawings")
		(19 "Cmts.User" user "User.Comments")
		(21 "Eco1.User" user "User.Eco1")
		(23 "Eco2.User" user "User.Eco2")
		(25 "Edge.Cuts" user "Board Geometry/Outline")
		(27 "Margin" user)
		(31 "F.CrtYd" user "Package Geometry/Place Bound Top")
		(29 "B.CrtYd" user "Package Geometry/Place Bound Bottom")
		(35 "F.Fab" user "Ref Des/Assembly Top")
		(33 "B.Fab" user "Ref Des/Assembly Bottom")
	)
	(footprint ""
		(layer "F.Cu")
		(at 270.000222 -76.550012 180)
		(property "Reference" "U5D1"
			(at 19.124422 31.601918 0)
			(unlocked yes)
			(layer "F.SilkS")
			(effects
				(font
					(size 0.7874 0.5842)
					(thickness 0.1524)
				)
			)
		)
		(property "Value" ""
			(at 0 0 180)
			(layer "F.Fab")
			(effects
				(font
					(size 1.27 1.27)
				)
			)
		)
		(duplicate_pad_numbers_are_jumpers no)
		(pad "BL8" smd circle
			(at -31.240984 -0.338074)
			(size 0.4318 0.4318)
			(layers "F.Cu" "F.Mask" "F.Paste")
			(net "P3E_CPU0_PE2_SS_RXN<14>")
		)
		(pad "BL10" smd circle
			(at -29.523944 -0.338074)
			(size 0.4318 0.4318)
			(layers "F.Cu" "F.Mask" "F.Paste")
			(net "GND")
		)
		(pad "BL12" smd circle
			(at -27.806904 -0.338074)
			(size 0.4318 0.4318)
			(layers "F.Cu" "F.Mask" "F.Paste")
			(net "GND")
		)
		(pad "BL14" smd circle
			(at -26.090118 -0.338074)
			(size 0.4318 0.4318)
			(layers "F.Cu" "F.Mask" "F.Paste")
			(net "PVCCMCP_CPU0")
		)
		(pad "BL16" smd circle
			(at -24.373078 -0.338074)
			(size 0.4318 0.4318)
			(layers "F.Cu" "F.Mask" "F.Paste")
			(net "VSENSE_PVCCMCP_CPU0_SKT_VRTN")
		)
		(pad "BL18" smd circle
			(at -22.656038 -0.338074)
			(size 0.4318 0.4318)
			(layers "F.Cu" "F.Mask" "F.Paste")
			(net "PVCCIOMCP_CPU0")
		)
		(pad "BL20" smd circle
			(at -20.938998 -0.338074)
			(size 0.4318 0.4318)
			(layers "F.Cu" "F.Mask" "F.Paste")
			(net "PVCCMCP_CPU0")
		)
		(pad "BL22" smd circle
			(at -19.221958 -0.338074)
			(size 0.4318 0.4318)
			(layers "F.Cu" "F.Mask" "F.Paste")
			(net "GND")
		)
		(pad "BL24" smd circle
			(at -17.504918 -0.338074)
			(size 0.4318 0.4318)
			(layers "F.Cu" "F.Mask" "F.Paste")
			(net "GND")
		)
		(pad "BL26" smd circle
			(at -15.787878 -0.338074)
			(size 0.4318 0.4318)
			(layers "F.Cu" "F.Mask" "F.Paste")
			(net "PVCCIO_CPU0")
		)
		(pad "BL60" smd circle
			(at 14.929612 -2.138426)
			(size 0.508 0.508)
			(layers "F.Cu" "F.Mask" "F.Paste")
			(net "PVCCIN_CPU0")
		)
		(pad "BL62" smd circle
			(at 16.646398 -2.138426)
			(size 0.4318 0.4318)
			(layers "F.Cu" "F.Mask" "F.Paste")
			(net "PVCCIN_CPU0")
		)
		(pad "BL64" smd circle
			(at 18.363438 -2.138426)
			(size 0.4318 0.4318)
			(layers "F.Cu" "F.Mask" "F.Paste")
			(net "GND")
		)
		(pad "BL66" smd circle
			(at 20.080478 -2.138426)
			(size 0.4318 0.4318)
			(layers "F.Cu" "F.Mask" "F.Paste")
			(net "GND")
		)
		(pad "BL68" smd circle
			(at 21.797518 -2.138426)
			(size 0.4318 0.4318)
			(layers "F.Cu" "F.Mask" "F.Paste")
			(net "GND")
		)
		(pad "BL70" smd circle
			(at 23.514558 -2.138426)
			(size 0.4318 0.4318)
			(layers "F.Cu" "F.Mask" "F.Paste")
			(net "GND")
		)
		(pad "BL72" smd circle
			(at 25.231598 -2.138426)
			(size 0.4318 0.4318)
			(layers "F.Cu" "F.Mask" "F.Paste")
			(net "GND")
		)
		(pad "BL74" smd circle
			(at 26.948384 -2.138426)
			(size 0.4318 0.4318)
			(layers "F.Cu" "F.Mask" "F.Paste")
			(net "GND")
		)
		(pad "BL76" smd circle
			(at 28.665424 -2.138426)
			(size 0.4318 0.4318)
			(layers "F.Cu" "F.Mask" "F.Paste")
			(net "GND")
		)
		(pad "BL78" smd circle
			(at 30.382464 -2.138426)
			(size 0.4318 0.4318)
			(layers "F.Cu" "F.Mask" "F.Paste")
			(net "GND")
		)
		(pad "BL80" smd circle
			(at 32.099504 -2.138426)
			(size 0.4318 0.4318)
			(layers "F.Cu" "F.Mask" "F.Paste")
			(net "GND")
		)
		(pad "BL82" smd circle
			(at 33.816544 -2.138426)
			(size 0.4318 0.4318)
			(layers "F.Cu" "F.Mask" "F.Paste")
			(net "GND")
		)
		(pad "BL84" smd custom
			(at 35.533584 -2.138426 270)
			(size 0.10795 0.10795)
			(layers "F.Cu" "F.Mask" "F.Paste")
			(net "PVCCIN_CPU0")
			(options
				(clearance outline)
				(anchor circle)
			)
			(primitives
				(gr_poly
					(pts
						(arc
							(start 0.2159 -0.0381)
							(mid 0 -0.254)
							(end -0.2159 -0.0381)
						)
						(arc
							(start -0.2159 0.0381)
							(mid 0 0.254)
							(end 0.2159 0.0381)
						)
					)
					(width 0)
					(fill yes)
				)
			)
		)
		(pad "BM3" smd custom
			(at -35.533584 0.156972 90)
			(size 0.10795 0.10795)
			(layers "F.Cu" "F.Mask" "F.Paste")
			(net "P3E_CPU0_PE2_SS_TXP<14>")
			(options
				(clearance outline)
				(anchor circle)
			)
			(primitives
				(gr_poly
					(pts
						(arc
							(start 0.2159 -0.0381)
							(mid 0 -0.254)
							(end -0.2159 -0.0381)
						)
						(arc
							(start -0.2159 0.0381)
							(mid 0 0.254)
							(end 0.2159 0.0381)
						)
					)
					(width 0)
					(fill yes)
				)
			)
		)
		(pad "BM5" smd circle
			(at -33.816544 0.156972)
			(size 0.4318 0.4318)
			(layers "F.Cu" "F.Mask" "F.Paste")
			(net "P3E_CPU0_PE2_SS_TXN<15>")
		)
		(pad "BM7" smd circle
			(at -32.099504 0.156972)
			(size 0.4318 0.4318)
			(layers "F.Cu" "F.Mask" "F.Paste")
			(net "P3E_CPU0_PE2_SS_RXP<13>")
		)
		(pad "BM9" smd circle
			(at -30.382464 0.156972)
			(size 0.4318 0.4318)
			(layers "F.Cu" "F.Mask" "F.Paste")
			(net "GND")
		)
		(pad "BM11" smd circle
			(at -28.665424 0.156972)
			(size 0.4318 0.4318)
			(layers "F.Cu" "F.Mask" "F.Paste")
			(net "PVCCIOMCP_CPU0")
		)
		(pad "BM13" smd circle
			(at -26.948384 0.156972)
			(size 0.4318 0.4318)
			(layers "F.Cu" "F.Mask" "F.Paste")
			(net "GND")
		)
		(pad "BM15" smd circle
			(at -25.231598 0.156972)
			(size 0.4318 0.4318)
			(layers "F.Cu" "F.Mask" "F.Paste")
			(net "GND")
		)
		(pad "BM17" smd circle
			(at -23.514558 0.156972)
			(size 0.4318 0.4318)
			(layers "F.Cu" "F.Mask" "F.Paste")
			(net "PVCCIOMCP_CPU0")
		)
		(pad "BM19" smd circle
			(at -21.797518 0.156972)
			(size 0.4318 0.4318)
			(layers "F.Cu" "F.Mask" "F.Paste")
			(net "PVCCMCP_CPU0")
		)
		(pad "BM21" smd circle
			(at -20.080478 0.156972)
			(size 0.4318 0.4318)
			(layers "F.Cu" "F.Mask" "F.Paste")
			(net "IRQ_HFI1_CPU0_LVT2_N")
		)
		(pad "BM23" smd circle
			(at -18.363438 0.156972)
			(size 0.4318 0.4318)
			(layers "F.Cu" "F.Mask" "F.Paste")
			(net "LED_HFI1_CPU0_N")
		)
		(pad "BM25" smd circle
			(at -16.646398 0.156972)
			(size 0.4318 0.4318)
			(layers "F.Cu" "F.Mask" "F.Paste")
			(net "GND")
		)
		(pad "BM27" smd circle
			(at -14.929612 0.156972)
			(size 0.4318 0.4318)
			(layers "F.Cu" "F.Mask" "F.Paste")
			(net "PVCCIO_CPU0")
		)
		(pad "BM61" smd circle
			(at 15.787878 -1.643126)
			(size 0.4318 0.4318)
			(layers "F.Cu" "F.Mask" "F.Paste")
			(net "PVCCIN_CPU0")
		)
		(pad "BM63" smd circle
			(at 17.504918 -1.643126)
			(size 0.4318 0.4318)
			(layers "F.Cu" "F.Mask" "F.Paste")
			(net "PVCCIN_CPU0")
		)
		(pad "BM65" smd circle
			(at 19.221958 -1.643126)
			(size 0.4318 0.4318)
			(layers "F.Cu" "F.Mask" "F.Paste")
			(net "PVCCIN_CPU0")
		)
		(pad "BM67" smd circle
			(at 20.938998 -1.643126)
			(size 0.4318 0.4318)
			(layers "F.Cu" "F.Mask" "F.Paste")
			(net "PVCCIN_CPU0")
		)
		(pad "BM69" smd circle
			(at 22.656038 -1.643126)
			(size 0.4318 0.4318)
			(layers "F.Cu" "F.Mask" "F.Paste")
			(net "PVCCIN_CPU0")
		)
		(pad "BM71" smd circle
			(at 24.373078 -1.643126)
			(size 0.4318 0.4318)
			(layers "F.Cu" "F.Mask" "F.Paste")
			(net "PVCCIN_CPU0")
		)
		(pad "BM73" smd circle
			(at 26.090118 -1.643126)
			(size 0.4318 0.4318)
			(layers "F.Cu" "F.Mask" "F.Paste")
			(net "PVCCIN_CPU0")
		)
		(pad "BM75" smd circle
			(at 27.806904 -1.643126)
			(size 0.4318 0.4318)
			(layers "F.Cu" "F.Mask" "F.Paste")
			(net "PVCCIN_CPU0")
		)
		(pad "BM77" smd circle
			(at 29.523944 -1.643126)
			(size 0.4318 0.4318)
			(layers "F.Cu" "F.Mask" "F.Paste")
			(net "PVCCIN_CPU0")
		)
		(pad "BM79" smd circle
			(at 31.240984 -1.643126)
			(size 0.4318 0.4318)
			(layers "F.Cu" "F.Mask" "F.Paste")
			(net "PVCCIN_CPU0")
		)
		(pad "BM81" smd circle
			(at 32.958024 -1.643126)
			(size 0.4318 0.4318)
			(layers "F.Cu" "F.Mask" "F.Paste")
			(net "PVCCIN_CPU0")
		)
		(pad "BM83" smd circle
			(at 34.675064 -1.643126)
			(size 0.4318 0.4318)
			(layers "F.Cu" "F.Mask" "F.Paste")
			(net "PVCCIN_CPU0")
		)
		(pad "BN4" smd circle
			(at -34.675064 0.652526)
			(size 0.4318 0.4318)
			(layers "F.Cu" "F.Mask" "F.Paste")
			(net "P3E_CPU0_PE2_SS_TXP<13>")
		)
		(pad "BN6" smd circle
			(at -32.958024 0.652526)
			(size 0.4318 0.4318)
			(layers "F.Cu" "F.Mask" "F.Paste")
			(net "GND")
		)
		(pad "BN8" smd circle
			(at -31.240984 0.652526)
			(size 0.4318 0.4318)
			(layers "F.Cu" "F.Mask" "F.Paste")
			(net "P3E_CPU0_PE2_SS_RXN<13>")
		)
		(pad "BN10" smd circle
			(at -29.523944 0.652526)
			(size 0.4318 0.4318)
			(layers "F.Cu" "F.Mask" "F.Paste")
			(net "GND")
		)
		(pad "BN12" smd circle
			(at -27.806904 0.652526)
			(size 0.4318 0.4318)
			(layers "F.Cu" "F.Mask" "F.Paste")
			(net "PVCCIOMCP_CPU0")
		)
		(pad "BN14" smd circle
			(at -26.090118 0.652526)
			(size 0.4318 0.4318)
			(layers "F.Cu" "F.Mask" "F.Paste")
			(net "PVCCIOMCP_CPU0")
		)
		(pad "BN16" smd circle
			(at -24.373078 0.652526)
			(size 0.4318 0.4318)
			(layers "F.Cu" "F.Mask" "F.Paste")
			(net "VSENSE_PVCCMCP_CPU0_SKT_VSEN")
		)
		(pad "BN18" smd circle
			(at -22.656038 0.652526)
			(size 0.4318 0.4318)
			(layers "F.Cu" "F.Mask" "F.Paste")
			(net "PVCCIOMCP_CPU0")
		)
		(pad "BN20" smd circle
			(at -20.938998 0.652526)
			(size 0.4318 0.4318)
			(layers "F.Cu" "F.Mask" "F.Paste")
			(net "GND")
		)
		(pad "BN22" smd circle
			(at -19.221958 0.652526)
			(size 0.4318 0.4318)
			(layers "F.Cu" "F.Mask" "F.Paste")
			(net "SMB_HFI0_CPU0_LVC2_SCL")
		)
		(pad "BN24" smd circle
			(at -17.504918 0.652526)
			(size 0.4318 0.4318)
			(layers "F.Cu" "F.Mask" "F.Paste")
			(net "RST_HFI0_CPU0_LVT2_N")
		)
		(pad "BN26" smd circle
			(at -15.787878 0.652526)
			(size 0.4318 0.4318)
			(layers "F.Cu" "F.Mask" "F.Paste")
			(net "GND")
		)
		(pad "BN60" smd circle
			(at 14.929612 -1.147572)
			(size 0.508 0.508)
			(layers "F.Cu" "F.Mask" "F.Paste")
			(net "PVCCIN_CPU0")
		)
		(pad "BN62" smd circle
			(at 16.646398 -1.147572)
			(size 0.4318 0.4318)
			(layers "F.Cu" "F.Mask" "F.Paste")
			(net "PVCCIN_CPU0")
		)
		(pad "BN64" smd circle
			(at 18.363438 -1.147572)
			(size 0.4318 0.4318)
			(layers "F.Cu" "F.Mask" "F.Paste")
			(net "PVCCIN_CPU0")
		)
		(pad "BN66" smd circle
			(at 20.080478 -1.147572)
			(size 0.4318 0.4318)
			(layers "F.Cu" "F.Mask" "F.Paste")
			(net "PVCCIN_CPU0")
		)
		(pad "BN68" smd circle
			(at 21.797518 -1.147572)
			(size 0.4318 0.4318)
			(layers "F.Cu" "F.Mask" "F.Paste")
			(net "PVCCIN_CPU0")
		)
		(pad "BN70" smd circle
			(at 23.514558 -1.147572)
			(size 0.4318 0.4318)
			(layers "F.Cu" "F.Mask" "F.Paste")
			(net "PVCCIN_CPU0")
		)
		(pad "BN72" smd circle
			(at 25.231598 -1.147572)
			(size 0.4318 0.4318)
			(layers "F.Cu" "F.Mask" "F.Paste")
			(net "PVCCIN_CPU0")
		)
		(pad "BN74" smd circle
			(at 26.948384 -1.147572)
			(size 0.4318 0.4318)
			(layers "F.Cu" "F.Mask" "F.Paste")
			(net "PVCCIN_CPU0")
		)
		(pad "BN76" smd circle
			(at 28.665424 -1.147572)
			(size 0.4318 0.4318)
			(layers "F.Cu" "F.Mask" "F.Paste")
			(net "PVCCIN_CPU0")
		)
		(pad "BN78" smd circle
			(at 30.382464 -1.147572)
			(size 0.4318 0.4318)
			(layers "F.Cu" "F.Mask" "F.Paste")
			(net "PVCCIN_CPU0")
		)
		(pad "BN80" smd circle
			(at 32.099504 -1.147572)
			(size 0.4318 0.4318)
			(layers "F.Cu" "F.Mask" "F.Paste")
			(net "PVCCIN_CPU0")
		)
		(pad "BN82" smd circle
			(at 33.816544 -1.147572)
			(size 0.4318 0.4318)
			(layers "F.Cu" "F.Mask" "F.Paste")
			(net "PVCCIN_CPU0")
		)
		(pad "BN84" smd custom
			(at 35.533584 -1.147572 270)
			(size 0.10795 0.10795)
			(layers "F.Cu" "F.Mask" "F.Paste")
			(net "PVCCIN_CPU0")
			(options
				(clearance outline)
				(anchor circle)
			)
			(primitives
				(gr_poly
					(pts
						(arc
							(start 0.2159 -0.0381)
							(mid 0 -0.254)
							(end -0.2159 -0.0381)
						)
						(arc
							(start -0.2159 0.0381)
							(mid 0 0.254)
							(end 0.2159 0.0381)
						)
					)
					(width 0)
					(fill yes)
				)
			)
		)
		(pad "BP3" smd custom
			(at -35.533584 1.147572 90)
			(size 0.10795 0.10795)
			(layers "F.Cu" "F.Mask" "F.Paste")
			(net "GND")
			(options
				(clearance outline)
				(anchor circle)
			)
			(primitives
				(gr_poly
					(pts
						(arc
							(start 0.2159 -0.0381)
							(mid 0 -0.254)
							(end -0.2159 -0.0381)
						)
						(arc
							(start -0.2159 0.0381)
							(mid 0 0.254)
							(end 0.2159 0.0381)
						)
					)
					(width 0)
					(fill yes)
				)
			)
		)
		(pad "BP5" smd circle
			(at -33.816544 1.147572)
			(size 0.4318 0.4318)
			(layers "F.Cu" "F.Mask" "F.Paste")
			(net "P3E_CPU0_PE2_SS_TXN<13>")
		)
		(pad "BP7" smd circle
			(at -32.099504 1.147572)
			(size 0.4318 0.4318)
			(layers "F.Cu" "F.Mask" "F.Paste")
			(net "P3E_CPU0_PE2_SS_RXP<11>")
		)
		(pad "BP9" smd circle
			(at -30.382464 1.147572)
			(size 0.4318 0.4318)
			(layers "F.Cu" "F.Mask" "F.Paste")
			(net "P3E_CPU0_PE2_SS_RXP<12>")
		)
		(pad "BP11" smd circle
			(at -28.665424 1.147572)
			(size 0.4318 0.4318)
			(layers "F.Cu" "F.Mask" "F.Paste")
			(net "PVCCIOMCP_CPU0")
		)
		(pad "BP13" smd circle
			(at -26.948384 1.147572)
			(size 0.4318 0.4318)
			(layers "F.Cu" "F.Mask" "F.Paste")
			(net "PVCCIOMCP_CPU0")
		)
		(pad "BP15" smd circle
			(at -25.231598 1.147572)
			(size 0.4318 0.4318)
			(layers "F.Cu" "F.Mask" "F.Paste")
			(net "PVCCIOMCP_CPU0")
		)
		(pad "BP17" smd circle
			(at -23.514558 1.147572)
			(size 0.4318 0.4318)
			(layers "F.Cu" "F.Mask" "F.Paste")
			(net "PVCCIOMCP_CPU0")
		)
		(pad "BP19" smd circle
			(at -21.797518 1.147572)
			(size 0.4318 0.4318)
			(layers "F.Cu" "F.Mask" "F.Paste")
			(net "IRQ_HFI0_CPU0_LVT2_N")
		)
		(pad "BP21" smd circle
			(at -20.080478 1.147572)
			(size 0.4318 0.4318)
			(layers "F.Cu" "F.Mask" "F.Paste")
			(net "PVCCMCP_CPU0")
		)
		(pad "BP23" smd circle
			(at -18.363438 1.147572)
			(size 0.4318 0.4318)
			(layers "F.Cu" "F.Mask" "F.Paste")
			(net "SMB_HFI0_CPU0_LVC2_SDA")
		)
		(pad "BP25" smd circle
			(at -16.646398 1.147572)
			(size 0.4318 0.4318)
			(layers "F.Cu" "F.Mask" "F.Paste")
			(net "PVCCIO_CPU0")
		)
		(pad "BP27" smd circle
			(at -14.929612 1.147572)
			(size 0.4318 0.4318)
			(layers "F.Cu" "F.Mask" "F.Paste")
			(net "GND")
		)
		(pad "BP61" smd circle
			(at 15.787878 -0.652526)
			(size 0.4318 0.4318)
			(layers "F.Cu" "F.Mask" "F.Paste")
			(net "PVCCIN_CPU0")
		)
		(pad "BP63" smd circle
			(at 17.504918 -0.652526)
			(size 0.4318 0.4318)
			(layers "F.Cu" "F.Mask" "F.Paste")
			(net "PVCCIN_CPU0")
		)
		(pad "BP65" smd circle
			(at 19.221958 -0.652526)
			(size 0.4318 0.4318)
			(layers "F.Cu" "F.Mask" "F.Paste")
			(net "PVCCIN_CPU0")
		)
		(pad "BP67" smd circle
			(at 20.938998 -0.652526)
			(size 0.4318 0.4318)
			(layers "F.Cu" "F.Mask" "F.Paste")
			(net "PVCCIN_CPU0")
		)
		(pad "BP69" smd circle
			(at 22.656038 -0.652526)
			(size 0.4318 0.4318)
			(layers "F.Cu" "F.Mask" "F.Paste")
			(net "PVCCIN_CPU0")
		)
		(pad "BP71" smd circle
			(at 24.373078 -0.652526)
			(size 0.4318 0.4318)
			(layers "F.Cu" "F.Mask" "F.Paste")
			(net "PVCCIN_CPU0")
		)
		(pad "BP73" smd circle
			(at 26.090118 -0.652526)
			(size 0.4318 0.4318)
			(layers "F.Cu" "F.Mask" "F.Paste")
			(net "PVCCIN_CPU0")
		)
		(pad "BP75" smd circle
			(at 27.806904 -0.652526)
			(size 0.4318 0.4318)
			(layers "F.Cu" "F.Mask" "F.Paste")
			(net "PVCCIN_CPU0")
		)
		(pad "BP77" smd circle
			(at 29.523944 -0.652526)
			(size 0.4318 0.4318)
			(layers "F.Cu" "F.Mask" "F.Paste")
			(net "PVCCIN_CPU0")
		)
		(pad "BP79" smd circle
			(at 31.240984 -0.652526)
			(size 0.4318 0.4318)
			(layers "F.Cu" "F.Mask" "F.Paste")
			(net "PVCCIN_CPU0")
		)
		(pad "BP81" smd circle
			(at 32.958024 -0.652526)
			(size 0.4318 0.4318)
			(layers "F.Cu" "F.Mask" "F.Paste")
			(net "PVCCIN_CPU0")
		)
		(pad "BP83" smd circle
			(at 34.675064 -0.652526)
			(size 0.4318 0.4318)
			(layers "F.Cu" "F.Mask" "F.Paste")
			(net "PVCCIN_CPU0")
		)
		(pad "BR4" smd circle
			(at -34.675064 1.643126)
			(size 0.4318 0.4318)
			(layers "F.Cu" "F.Mask" "F.Paste")
			(net "P3E_CPU0_PE2_SS_TXP<12>")
		)
		(pad "BR6" smd circle
			(at -32.958024 1.643126)
			(size 0.4318 0.4318)
			(layers "F.Cu" "F.Mask" "F.Paste")
			(net "GND")
		)
		(pad "BR8" smd circle
			(at -31.240984 1.643126)
			(size 0.4318 0.4318)
			(layers "F.Cu" "F.Mask" "F.Paste")
			(net "P3E_CPU0_PE2_SS_RXN<12>")
		)
		(pad "BR10" smd circle
			(at -29.523944 1.643126)
			(size 0.4318 0.4318)
			(layers "F.Cu" "F.Mask" "F.Paste")
			(net "GND")
		)
		(pad "BR12" smd circle
			(at -27.806904 1.643126)
			(size 0.4318 0.4318)
			(layers "F.Cu" "F.Mask" "F.Paste")
			(net "PVCCIOMCP_CPU0")
		)
		(pad "BR14" smd circle
			(at -26.090118 1.643126)
			(size 0.4318 0.4318)
			(layers "F.Cu" "F.Mask" "F.Paste")
			(net "PVCCIOMCP_CPU0")
		)
		(pad "BR16" smd circle
			(at -24.373078 1.643126)
			(size 0.4318 0.4318)
			(layers "F.Cu" "F.Mask" "F.Paste")
			(net "GND")
		)
		(pad "BR18" smd circle
			(at -22.656038 1.643126)
			(size 0.4318 0.4318)
			(layers "F.Cu" "F.Mask" "F.Paste")
			(net "GND")
		)
	)
)
